# S9S_MB_2U (Grand Teton) — schematic netlist excerpt (pin names and nets, part order shuffled) for the footprints in the layout excerpt that follows; sources: Cadence DE-HDL packaged netlist, KiCad conversion of 03242023_DA0F0TMBIJ0_F0T_Motherboard_J_brd_V01_OCP.brd

J21  SCONN288_ADR50017P130CC  SCONN288_ADR50017-P130CC IO  pkg DDR288S_1-1VXB  page 102
  VIN_BULK0  = P12V_S3_AUX_CPU1_NVDIMM
  RFU0  = TP_CHC_CPU1_DIMM1_FRU_0
  VIN_MGMT  = P3V3_AUX
  HSCL  = I3C_SPD_DDRABCD_CPU1_LVC1_SCL_4
  HSDA  = I3C_SPD_DDRABCD_CPU1_LVC1_SDA
  VSS0  = GND
  DQ0_A  = M_C_CPU1_SA_DQ<0>
  VSS1  = GND
  DQ1_A  = M_C_CPU1_SA_DQ<1>
  VSS2  = GND
  DQS0_A_T  = M_C_CPU1_SA_DQS_DP<0>
  DQS0_A_C  = M_C_CPU1_SA_DQS_DN<0>
  VSS3  = GND
  DQ4_A  = M_C_CPU1_SA_DQ<4>
  VSS4  = GND
  DQ5_A  = M_C_CPU1_SA_DQ<5>
  VSS5  = GND
  DQ8_A  = M_C_CPU1_SA_DQ<8>
  VSS6  = GND
  DQ9_A  = M_C_CPU1_SA_DQ<9>
  VSS7  = GND
  DQS1_A_T  = M_C_CPU1_SA_DQS_DP<1>
  DQS1_A_C  = M_C_CPU1_SA_DQS_DN<1>
  VSS8  = GND
  DQ12_A  = M_C_CPU1_SA_DQ<12>
  VSS9  = GND
  DQ13_A  = M_C_CPU1_SA_DQ<13>
  VSS10  = GND
  DQ16_A  = M_C_CPU1_SA_DQ<16>
  VSS11  = GND
  DQ17_A  = M_C_CPU1_SA_DQ<17>
  VSS12  = GND
  DQS2_A_T  = M_C_CPU1_SA_DQS_DP<2>
  DQS2_A_C  = M_C_CPU1_SA_DQS_DN<2>
  VSS13  = GND
  DQ20_A  = M_C_CPU1_SA_DQ<20>
  VSS14  = GND
  DQ21_A  = M_C_CPU1_SA_DQ<21>
  VSS15  = GND
  DQ24_A  = M_C_CPU1_SA_DQ<24>
  VSS16  = GND
  DQ25_A  = M_C_CPU1_SA_DQ<25>
  VSS17  = GND
  DQS3_A_T  = M_C_CPU1_SA_DQS_DP<3>
  DQS3_A_C  = M_C_CPU1_SA_DQS_DN<3>
  VSS18  = GND
  DQ28_A  = M_C_CPU1_SA_DQ<28>
  VSS19  = GND
  DQ29_A  = M_C_CPU1_SA_DQ<29>
  VSS20  = GND
  CB0_A  = M_C_CPU1_SA_CB<0>
  VSS21  = GND
  CB1_A  = M_C_CPU1_SA_CB<1>
  VSS22  = GND
  DQS4_A_T  = M_C_CPU1_SA_DQS_DP<4>
  DQS4_A_C  = M_C_CPU1_SA_DQS_DN<4>
  VSS23  = GND
  CB4_A  = M_C_CPU1_SA_CB<4>
  VSS24  = GND
  CB5_A  = M_C_CPU1_SA_CB<5>
  VSS25  = GND
  ALERT_N  = M_C_CPU1_ALERT_N
  VSS26  = GND
  CS0_A_N  = M_C_CPU1_SA_CS_N<0>
  VSS27  = GND
  CA0_A  = M_C_CPU1_SA_CA<0>
  VSS28  = GND
  CA2_A  = M_C_CPU1_SA_CA<2>
  VSS29  = GND
  CA4_A  = M_C_CPU1_SA_CA<4>
  VSS30  = GND
  CA6_A  = M_C_CPU1_SA_CA<6>
  VSS31  = GND
  PAR_A  = M_C_CPU1_SA_PAR
  VSS32  = GND
  CA0_B  = M_C_CPU1_SB_CA<0>
  VSS33  = GND
  CA2_B  = M_C_CPU1_SB_CA<2>
  VSS34  = GND
  CA4_B  = M_C_CPU1_SB_CA<4>
  VSS35  = GND
  CA6_B  = M_C_CPU1_SB_CA<6>
  VSS36  = GND
  CS0_B_N  = M_C_CPU1_SB_CS_N<0>
  VSS37  = GND
  \lbd||rsp_a_n\  = M_C_CPU1_SA_RSP<0>
  \lbs||rsp_b_n\  = M_C_CPU1_SB_RSP<0>
  VSS38  = GND
  CB4_B  = M_C_CPU1_SB_CB<4>
  VSS39  = GND
  CB5_B  = M_C_CPU1_SB_CB<5>
  VSS40  = GND
  \dqs9_b_t||tdqs9_b_t||dbi4_b_n\  = M_C_CPU1_SB_DQS_DP<9>
  \dqs9_b_c||tdqs9_b_c\  = M_C_CPU1_SB_DQS_DN<9>
  VSS41  = GND
  CB0_B  = M_C_CPU1_SB_CB<0>
  VSS42  = GND
  CB1_B  = M_C_CPU1_SB_CB<1>
  VSS43  = GND
  DQ0_B  = M_C_CPU1_SB_DQ<0>
  VSS44  = GND
  DQ1_B  = M_C_CPU1_SB_DQ<1>
  VSS45  = GND
  DQS0_B_T  = M_C_CPU1_SB_DQS_DP<0>
  DQS0_B_C  = M_C_CPU1_SB_DQS_DN<0>
  VSS46  = GND
  DQ4_B  = M_C_CPU1_SB_DQ<4>
  VSS47  = GND
  DQ5_B  = M_C_CPU1_SB_DQ<5>
  VSS48  = GND
  DQ8_B  = M_C_CPU1_SB_DQ<8>
  VSS49  = GND
  DQ9_B  = M_C_CPU1_SB_DQ<9>
  VSS50  = GND
  DQS1_B_T  = M_C_CPU1_SB_DQS_DP<1>
  DQS1_B_C  = M_C_CPU1_SB_DQS_DN<1>
  VSS51  = GND
  DQ12_B  = M_C_CPU1_SB_DQ<12>
  VSS52  = GND
  DQ13_B  = M_C_CPU1_SB_DQ<13>
  VSS53  = GND
  DQ16_B  = M_C_CPU1_SB_DQ<16>
  VSS54  = GND
  DQ17_B  = M_C_CPU1_SB_DQ<17>
  VSS55  = GND
  DQS2_B_T  = M_C_CPU1_SB_DQS_DP<2>
  DQS2_B_C  = M_C_CPU1_SB_DQS_DN<2>
  VSS56  = GND
  DQ20_B  = M_C_CPU1_SB_DQ<20>
  VSS57  = GND
  DQ21_B  = M_C_CPU1_SB_DQ<21>
  VSS58  = GND
  DQ24_B  = M_C_CPU1_SB_DQ<24>
  VSS59  = GND
  DQ25_B  = M_C_CPU1_SB_DQ<25>
  VSS60  = GND
  DQS3_B_T  = M_C_CPU1_SB_DQS_DP<3>
  DQS3_B_C  = M_C_CPU1_SB_DQS_DN<3>
  VSS61  = GND
  DQ28_B  = M_C_CPU1_SB_DQ<28>
  VSS62  = GND
  DQ29_B  = M_C_CPU1_SB_DQ<29>
  VSS63  = GND
  RFU1  = TP_CHC_CPU1_DIMM1_FRU_1
  VIN_BULK1  = P12V_S3_AUX_CPU1_NVDIMM
  VIN_BULK2  = P12V_S3_AUX_CPU1_NVDIMM
  \pwr_good||fail_n\  = PWRGD_CHC_CPU1_DIMM1
  HSA  = PD_CHC_CPU1_DIMM1_SAA
  RFU2  = TP_CHC_CPU1_DIMM1_FRU_2
  RFU3  = TP_CHC_CPU1_DIMM1_FRU_3
  VSS64  = GND
  DQ2_A  = M_C_CPU1_SA_DQ<2>
  VSS65  = GND
  DQ3_A  = M_C_CPU1_SA_DQ<3>
  VSS66  = GND
  \dqs5_a_c||tdqs5_a_c||dqs5_a_t||tdqs5_a_t\  = M_C_CPU1_SA_DQS_DN<5>
  \dqs5_a_t||tdqs5_a_t\  = M_C_CPU1_SA_DQS_DP<5>
  VSS67  = GND
  DQ6_A  = M_C_CPU1_SA_DQ<6>
  VSS68  = GND
  DQ7_A  = M_C_CPU1_SA_DQ<7>
  VSS69  = GND
  DQ10_A  = M_C_CPU1_SA_DQ<10>
  VSS70  = GND
  DQ11_A  = M_C_CPU1_SA_DQ<11>
  VSS71  = GND
  \dqs6_a_c||tdqs6_a_c||dqs6_a_t||tdqs6_a_t\  = M_C_CPU1_SA_DQS_DN<6>
  \dqs6_a_t||tdqs6_a_t\  = M_C_CPU1_SA_DQS_DP<6>
  VSS72  = GND
  DQ14_A  = M_C_CPU1_SA_DQ<14>
  VSS73  = GND
  DQ15_A  = M_C_CPU1_SA_DQ<15>
  VSS74  = GND
  DQ18_A  = M_C_CPU1_SA_DQ<18>
  VSS75  = GND
  DQ19_A  = M_C_CPU1_SA_DQ<19>
  VSS76  = GND
  \dqs7_a_c||tdqs7_a_c\  = M_C_CPU1_SA_DQS_DN<7>
  \dqs7_a_t||tdqs7_a_t\  = M_C_CPU1_SA_DQS_DP<7>
  VSS77  = GND
  DQ22_A  = M_C_CPU1_SA_DQ<22>
  VSS78  = GND
  DQ23_A  = M_C_CPU1_SA_DQ<23>
  VSS79  = GND
  DQ26_A  = M_C_CPU1_SA_DQ<26>
  VSS80  = GND
  DQ27_A  = M_C_CPU1_SA_DQ<27>
  VSS81  = GND
  \dqs8_a_c||tdqs8_a_c\  = M_C_CPU1_SA_DQS_DN<8>
  \dqs8_a_t||tdqs8_a_t\  = M_C_CPU1_SA_DQS_DP<8>
  VSS82  = GND
  DQ30_A  = M_C_CPU1_SA_DQ<30>
  VSS83  = GND
  DQ31_A  = M_C_CPU1_SA_DQ<31>
  VSS84  = GND
  CB2_A  = M_C_CPU1_SA_CB<2>
  VSS85  = GND
  CB3_A  = M_C_CPU1_SA_CB<3>
  VSS86  = GND
  \dqs9_a_c||tdqs9_a_c\  = M_C_CPU1_SA_DQS_DN<9>
  \dqs9_a_t||tdqs9_a_t\  = M_C_CPU1_SA_DQS_DP<9>
  VSS87  = GND
  CB6_A  = M_C_CPU1_SA_CB<6>
  VSS88  = GND
  CB7_A  = M_C_CPU1_SA_CB<7>
  VSS89  = GND
  RESET_N  = RST_M_CD_CPU1_FPGA_N
  VSS90  = GND
  CS1_A_N  = M_C_CPU1_SA_CS_N<1>
  VSS91  = GND
  CA1_A  = M_C_CPU1_SA_CA<1>
  VSS92  = GND
  CA3_A  = M_C_CPU1_SA_CA<3>
  VSS93  = GND
  CA5_A  = M_C_CPU1_SA_CA<5>
  VSS94  = GND
  CK_T  = M_C_CPU1_CLK_DP<0>
  CK_C  = M_C_CPU1_CLK_DN<0>
  VSS95  = GND
  RFU4  = TP_CHC_CPU1_DIMM1_FRU_4
  CA1_B  = M_C_CPU1_SB_CA<1>
  VSS96  = GND
  CA3_B  = M_C_CPU1_SB_CA<3>
  VSS97  = GND
  CA5_B  = M_C_CPU1_SB_CA<5>
  VSS98  = GND
  PAR_B  = M_C_CPU1_SB_PAR
  VSS99  = GND
  CS1_B_N  = M_C_CPU1_SB_CS_N<1>
  VSS100  = GND
  RFU5  = TP_CHC_CPU1_DIMM1_FRU_5
  RFU6  = TP_CHC_CPU1_DIMM1_FRU_6
  VSS101  = GND
  CB6_B  = M_C_CPU1_SB_CB<6>
  VSS102  = GND
  CB7_B  = M_C_CPU1_SB_CB<7>
  VSS103  = GND
  DQS4_B_C  = M_C_CPU1_SB_DQS_DN<4>
  DQS4_B_T  = M_C_CPU1_SB_DQS_DP<4>
  VSS104  = GND
  CB2_B  = M_C_CPU1_SB_CB<2>
  VSS105  = GND
  CB3_B  = M_C_CPU1_SB_CB<3>
  VSS106  = GND
  DQ2_B  = M_C_CPU1_SB_DQ<2>
  VSS107  = GND
  DQ3_B  = M_C_CPU1_SB_DQ<3>
  VSS108  = GND
  \dqs5_b_c||tdqs5_b_c\  = M_C_CPU1_SB_DQS_DN<5>
  \dqs5_b_t||tdqs5_b_t\  = M_C_CPU1_SB_DQS_DP<5>
  VSS109  = GND
  DQ6_B  = M_C_CPU1_SB_DQ<6>
  VSS110  = GND
  DQ7_B  = M_C_CPU1_SB_DQ<7>
  VSS111  = GND
  DQ10_B  = M_C_CPU1_SB_DQ<10>
  VSS112  = GND
  DQ11_B  = M_C_CPU1_SB_DQ<11>
  VSS113  = GND
  \dqs6_b_c||tdqs6_b_c\  = M_C_CPU1_SB_DQS_DN<6>
  \dqs6_b_t||tdqs6_b_t\  = M_C_CPU1_SB_DQS_DP<6>
  VSS114  = GND
  DQ14_B  = M_C_CPU1_SB_DQ<14>
  VSS115  = GND
  DQ15_B  = M_C_CPU1_SB_DQ<15>
  VSS116  = GND
  DQ18_B  = M_C_CPU1_SB_DQ<18>
  VSS117  = GND
  DQ19_B  = M_C_CPU1_SB_DQ<19>
  VSS118  = GND
  \dqs7_b_c||tdqs7_b_c\  = M_C_CPU1_SB_DQS_DN<7>
  \dqs7_b_t||tdqs7_b_t\  = M_C_CPU1_SB_DQS_DP<7>
  VSS119  = GND
  DQ22_B  = M_C_CPU1_SB_DQ<22>
  VSS120  = GND
  DQ23_B  = M_C_CPU1_SB_DQ<23>
  VSS121  = GND
  DQ26_B  = M_C_CPU1_SB_DQ<26>
  VSS122  = GND
  DQ27_B  = M_C_CPU1_SB_DQ<27>
  VSS123  = GND
  \dqs8_b_c||tdqs8_b_c\  = M_C_CPU1_SB_DQS_DN<8>
  \dqs8_b_t||tdqs8_b_t\  = M_C_CPU1_SB_DQS_DP<8>
  VSS124  = GND
  DQ30_B  = M_C_CPU1_SB_DQ<30>
  VSS125  = GND
  DQ31_B  = M_C_CPU1_SB_DQ<31>
  VSS126  = GND
  G1  = GND
  G2  = GND
  G3  = GND

(kicad_pcb
	(version 20260206)
	(generator "pcbnew")
	(generator_version "10.0")
	(general
		(thickness 1.6)
		(legacy_teardrops no)
	)
	(paper "A4")
	(title_block
		(title "03242023_DA0F0TMBIJ0_F0T_Motherboard_J_brd_V01_OCP.brd")
		(comment 1 "Grand Teton / footprint 663 of 6105 (J21), pads 92-137 of 291")
	)
	(layers
		(0 "F.Cu" signal "TOP")
		(4 "In1.Cu" signal "GND")
		(6 "In2.Cu" signal "IN1")
		(8 "In3.Cu" signal "GND1")
		(10 "In4.Cu" signal "IN2")
		(12 "In5.Cu" signal "GND2")
		(14 "In6.Cu" signal "IN3")
		(16 "In7.Cu" signal "GND3")
		(18 "In8.Cu" signal "VCC")
		(20 "In9.Cu" signal "VCC1")
		(22 "In10.Cu" signal "GND4")
		(24 "In11.Cu" signal "IN4")
		(26 "In12.Cu" signal "GND5")
		(28 "In13.Cu" signal "IN5")
		(30 "In14.Cu" signal "GND6")
		(32 "In15.Cu" signal "IN6")
		(34 "In16.Cu" signal "GND7")
		(2 "B.Cu" signal "BOTTOM")
		(9 "F.Adhes" user "F.Adhesive")
		(11 "B.Adhes" user "B.Adhesive")
		(13 "F.Paste" user "Package Geometry/Pastemask Top")
		(15 "B.Paste" user "Package Geometry/Pastemask Bottom")
		(5 "F.SilkS" user "Ref Des/Silkscreen Top")
		(7 "B.SilkS" user "Ref Des/Silkscreen Bottom")
		(1 "F.Mask" user "Board Geometry/Soldermask Top")
		(3 "B.Mask" user "Board Geometry/Soldermask Bottom")
		(17 "Dwgs.User" user "User.Drawings")
		(19 "Cmts.User" user "User.Comments")
		(21 "Eco1.User" user "User.Eco1")
		(23 "Eco2.User" user "User.Eco2")
		(25 "Edge.Cuts" user "Board Geometry/Outline")
		(27 "Margin" user)
		(31 "F.CrtYd" user "Package Geometry/Place Bound Top")
		(29 "B.CrtYd" user "Package Geometry/Place Bound Bottom")
		(35 "F.Fab" user "Ref Des/Assembly Top")
		(33 "B.Fab" user "Ref Des/Assembly Bottom")
	)
	(footprint ""
		(layer "F.Cu")
		(at 25.27808 -258.091686)
		(property "Reference" "J21"
			(at -0.325882 -81.821274 0)
			(unlocked yes)
			(layer "F.SilkS")
			(effects
				(font
					(size 0.7874 0.5842)
					(thickness 0.1524)
				)
				(justify left)
			)
		)
		(property "Value" ""
			(at 0 0 0)
			(layer "F.Fab")
			(effects
				(font
					(size 1.27 1.27)
				)
			)
		)
		(duplicate_pad_numbers_are_jumpers no)
		(pad "92" smd rect
			(at -2.050034 19.12493 270)
			(size 0.519938 1.4986)
			(layers "F.Cu" "F.Mask" "F.Paste")
			(net "GND")
		)
		(pad "93" smd rect
			(at -2.050034 19.975068 270)
			(size 0.519938 1.4986)
			(layers "F.Cu" "F.Mask" "F.Paste")
			(net "M_C_CPU1_SB_DQS_DP<9>")
		)
		(pad "94" smd rect
			(at -2.050034 20.824952 270)
			(size 0.519938 1.4986)
			(layers "F.Cu" "F.Mask" "F.Paste")
			(net "M_C_CPU1_SB_DQS_DN<9>")
		)
		(pad "95" smd rect
			(at -2.050034 21.67509 270)
			(size 0.519938 1.4986)
			(layers "F.Cu" "F.Mask" "F.Paste")
			(net "GND")
		)
		(pad "96" smd rect
			(at -2.050034 22.524974 270)
			(size 0.519938 1.4986)
			(layers "F.Cu" "F.Mask" "F.Paste")
			(net "M_C_CPU1_SB_CB<0>")
		)
		(pad "97" smd rect
			(at -2.050034 23.375112 270)
			(size 0.519938 1.4986)
			(layers "F.Cu" "F.Mask" "F.Paste")
			(net "GND")
		)
		(pad "98" smd rect
			(at -2.050034 24.224996 270)
			(size 0.519938 1.4986)
			(layers "F.Cu" "F.Mask" "F.Paste")
			(net "M_C_CPU1_SB_CB<1>")
		)
		(pad "99" smd rect
			(at -2.050034 25.07488 270)
			(size 0.519938 1.4986)
			(layers "F.Cu" "F.Mask" "F.Paste")
			(net "GND")
		)
		(pad "100" smd rect
			(at -2.050034 25.925018 270)
			(size 0.519938 1.4986)
			(layers "F.Cu" "F.Mask" "F.Paste")
			(net "M_C_CPU1_SB_DQ<0>")
		)
		(pad "101" smd rect
			(at -2.050034 26.774902 270)
			(size 0.519938 1.4986)
			(layers "F.Cu" "F.Mask" "F.Paste")
			(net "GND")
		)
		(pad "102" smd rect
			(at -2.050034 27.62504 270)
			(size 0.519938 1.4986)
			(layers "F.Cu" "F.Mask" "F.Paste")
			(net "M_C_CPU1_SB_DQ<1>")
		)
		(pad "103" smd rect
			(at -2.050034 28.474924 270)
			(size 0.519938 1.4986)
			(layers "F.Cu" "F.Mask" "F.Paste")
			(net "GND")
		)
		(pad "104" smd rect
			(at -2.050034 29.325062 270)
			(size 0.519938 1.4986)
			(layers "F.Cu" "F.Mask" "F.Paste")
			(net "M_C_CPU1_SB_DQS_DP<0>")
		)
		(pad "105" smd rect
			(at -2.050034 30.174946 270)
			(size 0.519938 1.4986)
			(layers "F.Cu" "F.Mask" "F.Paste")
			(net "M_C_CPU1_SB_DQS_DN<0>")
		)
		(pad "106" smd rect
			(at -2.050034 31.025084 270)
			(size 0.519938 1.4986)
			(layers "F.Cu" "F.Mask" "F.Paste")
			(net "GND")
		)
		(pad "107" smd rect
			(at -2.050034 31.874968 270)
			(size 0.519938 1.4986)
			(layers "F.Cu" "F.Mask" "F.Paste")
			(net "M_C_CPU1_SB_DQ<4>")
		)
		(pad "108" smd rect
			(at -2.050034 32.725106 270)
			(size 0.519938 1.4986)
			(layers "F.Cu" "F.Mask" "F.Paste")
			(net "GND")
		)
		(pad "109" smd rect
			(at -2.050034 33.57499 270)
			(size 0.519938 1.4986)
			(layers "F.Cu" "F.Mask" "F.Paste")
			(net "M_C_CPU1_SB_DQ<5>")
		)
		(pad "110" smd rect
			(at -2.050034 34.425128 270)
			(size 0.519938 1.4986)
			(layers "F.Cu" "F.Mask" "F.Paste")
			(net "GND")
		)
		(pad "111" smd rect
			(at -2.050034 35.275012 270)
			(size 0.519938 1.4986)
			(layers "F.Cu" "F.Mask" "F.Paste")
			(net "M_C_CPU1_SB_DQ<8>")
		)
		(pad "112" smd rect
			(at -2.050034 36.124896 270)
			(size 0.519938 1.4986)
			(layers "F.Cu" "F.Mask" "F.Paste")
			(net "GND")
		)
		(pad "113" smd rect
			(at -2.050034 36.975034 270)
			(size 0.519938 1.4986)
			(layers "F.Cu" "F.Mask" "F.Paste")
			(net "M_C_CPU1_SB_DQ<9>")
		)
		(pad "114" smd rect
			(at -2.050034 37.824918 270)
			(size 0.519938 1.4986)
			(layers "F.Cu" "F.Mask" "F.Paste")
			(net "GND")
		)
		(pad "115" smd rect
			(at -2.050034 38.675056 270)
			(size 0.519938 1.4986)
			(layers "F.Cu" "F.Mask" "F.Paste")
			(net "M_C_CPU1_SB_DQS_DP<1>")
		)
		(pad "116" smd rect
			(at -2.050034 39.52494 270)
			(size 0.519938 1.4986)
			(layers "F.Cu" "F.Mask" "F.Paste")
			(net "M_C_CPU1_SB_DQS_DN<1>")
		)
		(pad "117" smd rect
			(at -2.050034 40.375078 270)
			(size 0.519938 1.4986)
			(layers "F.Cu" "F.Mask" "F.Paste")
			(net "GND")
		)
		(pad "118" smd rect
			(at -2.050034 41.224962 270)
			(size 0.519938 1.4986)
			(layers "F.Cu" "F.Mask" "F.Paste")
			(net "M_C_CPU1_SB_DQ<12>")
		)
		(pad "119" smd rect
			(at -2.050034 42.0751 270)
			(size 0.519938 1.4986)
			(layers "F.Cu" "F.Mask" "F.Paste")
			(net "GND")
		)
		(pad "120" smd rect
			(at -2.050034 42.924984 270)
			(size 0.519938 1.4986)
			(layers "F.Cu" "F.Mask" "F.Paste")
			(net "M_C_CPU1_SB_DQ<13>")
		)
		(pad "121" smd rect
			(at -2.050034 43.775122 270)
			(size 0.519938 1.4986)
			(layers "F.Cu" "F.Mask" "F.Paste")
			(net "GND")
		)
		(pad "122" smd rect
			(at -2.050034 44.625006 270)
			(size 0.519938 1.4986)
			(layers "F.Cu" "F.Mask" "F.Paste")
			(net "M_C_CPU1_SB_DQ<16>")
		)
		(pad "123" smd rect
			(at -2.050034 45.47489 270)
			(size 0.519938 1.4986)
			(layers "F.Cu" "F.Mask" "F.Paste")
			(net "GND")
		)
		(pad "124" smd rect
			(at -2.050034 46.325028 270)
			(size 0.519938 1.4986)
			(layers "F.Cu" "F.Mask" "F.Paste")
			(net "M_C_CPU1_SB_DQ<17>")
		)
		(pad "125" smd rect
			(at -2.050034 47.174912 270)
			(size 0.519938 1.4986)
			(layers "F.Cu" "F.Mask" "F.Paste")
			(net "GND")
		)
		(pad "126" smd rect
			(at -2.050034 48.02505 270)
			(size 0.519938 1.4986)
			(layers "F.Cu" "F.Mask" "F.Paste")
			(net "M_C_CPU1_SB_DQS_DP<2>")
		)
		(pad "127" smd rect
			(at -2.050034 48.874934 270)
			(size 0.519938 1.4986)
			(layers "F.Cu" "F.Mask" "F.Paste")
			(net "M_C_CPU1_SB_DQS_DN<2>")
		)
		(pad "128" smd rect
			(at -2.050034 49.725072 270)
			(size 0.519938 1.4986)
			(layers "F.Cu" "F.Mask" "F.Paste")
			(net "GND")
		)
		(pad "129" smd rect
			(at -2.050034 50.574956 270)
			(size 0.519938 1.4986)
			(layers "F.Cu" "F.Mask" "F.Paste")
			(net "M_C_CPU1_SB_DQ<20>")
		)
		(pad "130" smd rect
			(at -2.050034 51.425094 270)
			(size 0.519938 1.4986)
			(layers "F.Cu" "F.Mask" "F.Paste")
			(net "GND")
		)
		(pad "131" smd rect
			(at -2.050034 52.274978 270)
			(size 0.519938 1.4986)
			(layers "F.Cu" "F.Mask" "F.Paste")
			(net "M_C_CPU1_SB_DQ<21>")
		)
		(pad "132" smd rect
			(at -2.050034 53.125116 270)
			(size 0.519938 1.4986)
			(layers "F.Cu" "F.Mask" "F.Paste")
			(net "GND")
		)
		(pad "133" smd rect
			(at -2.050034 53.975 270)
			(size 0.519938 1.4986)
			(layers "F.Cu" "F.Mask" "F.Paste")
			(net "M_C_CPU1_SB_DQ<24>")
		)
		(pad "134" smd rect
			(at -2.050034 54.824884 270)
			(size 0.519938 1.4986)
			(layers "F.Cu" "F.Mask" "F.Paste")
			(net "GND")
		)
		(pad "135" smd rect
			(at -2.050034 55.675022 270)
			(size 0.519938 1.4986)
			(layers "F.Cu" "F.Mask" "F.Paste")
			(net "M_C_CPU1_SB_DQ<25>")
		)
		(pad "136" smd rect
			(at -2.050034 56.524906 270)
			(size 0.519938 1.4986)
			(layers "F.Cu" "F.Mask" "F.Paste")
			(net "GND")
		)
		(pad "137" smd rect
			(at -2.050034 57.375044 270)
			(size 0.519938 1.4986)
			(layers "F.Cu" "F.Mask" "F.Paste")
			(net "M_C_CPU1_SB_DQS_DP<3>")
		)
	)
)
